# S9S_MB_2U (Grand Teton) — schematic netlist excerpt (pin names and nets, part order shuffled) for the footprints in the layout excerpt that follows; sources: Cadence DE-HDL packaged netlist, KiCad conversion of 03242023_DA0F0TMBIJ0_F0T_Motherboard_J_brd_V01_OCP.brd

R4299  Q_RES  100 1% CHIP  pkg 0402LF  page 125 : A = PWRGD_DRAMPWRGD_CPU1_AB_LVC1_R2 ; B = PWRGD_DRAMPWRGD_CPU1_AB_LVC1_R
R2244  Q_RES  10K 1% CHIP  pkg 0402LF  page 220 : A = ROT_P1_RST_IND_N_R ; B = P3V3_AUX

(kicad_pcb
	(version 20260206)
	(generator "pcbnew")
	(generator_version "10.0")
	(general
		(thickness 1.6)
		(legacy_teardrops no)
	)
	(paper "A4")
	(title_block
		(title "03242023_DA0F0TMBIJ0_F0T_Motherboard_J_brd_V01_OCP.brd")
		(comment 1 "Grand Teton / footprints 5491-5492 of 6105")
	)
	(layers
		(0 "F.Cu" signal "TOP")
		(4 "In1.Cu" signal "GND")
		(6 "In2.Cu" signal "IN1")
		(8 "In3.Cu" signal "GND1")
		(10 "In4.Cu" signal "IN2")
		(12 "In5.Cu" signal "GND2")
		(14 "In6.Cu" signal "IN3")
		(16 "In7.Cu" signal "GND3")
		(18 "In8.Cu" signal "VCC")
		(20 "In9.Cu" signal "VCC1")
		(22 "In10.Cu" signal "GND4")
		(24 "In11.Cu" signal "IN4")
		(26 "In12.Cu" signal "GND5")
		(28 "In13.Cu" signal "IN5")
		(30 "In14.Cu" signal "GND6")
		(32 "In15.Cu" signal "IN6")
		(34 "In16.Cu" signal "GND7")
		(2 "B.Cu" signal "BOTTOM")
		(9 "F.Adhes" user "F.Adhesive")
		(11 "B.Adhes" user "B.Adhesive")
		(13 "F.Paste" user "Package Geometry/Pastemask Top")
		(15 "B.Paste" user "Package Geometry/Pastemask Bottom")
		(5 "F.SilkS" user "Ref Des/Silkscreen Top")
		(7 "B.SilkS" user "Ref Des/Silkscreen Bottom")
		(1 "F.Mask" user "Board Geometry/Soldermask Top")
		(3 "B.Mask" user "Board Geometry/Soldermask Bottom")
		(17 "Dwgs.User" user "User.Drawings")
		(19 "Cmts.User" user "User.Comments")
		(21 "Eco1.User" user "User.Eco1")
		(23 "Eco2.User" user "User.Eco2")
		(25 "Edge.Cuts" user "Board Geometry/Outline")
		(27 "Margin" user)
		(31 "F.CrtYd" user "Package Geometry/Place Bound Top")
		(29 "B.CrtYd" user "Package Geometry/Place Bound Bottom")
		(35 "F.Fab" user "Ref Des/Assembly Top")
		(33 "B.Fab" user "Ref Des/Assembly Bottom")
	)
	(footprint ""
		(layer "B.Cu")
		(at 193.38036 -119.344948 180)
		(property "Reference" "R2244"
			(at 0 0 0)
			(layer "B.SilkS")
			(hide yes)
			(effects
				(font
					(size 1.27 1.27)
				)
				(justify mirror)
			)
		)
		(property "Value" ""
			(at 0 0 0)
			(layer "B.Fab")
			(effects
				(font
					(size 1.27 1.27)
				)
				(justify mirror)
			)
		)
		(duplicate_pad_numbers_are_jumpers no)
		(fp_line
			(start 0.7874 0.4064)
			(end 0.7874 -0.4064)
			(stroke
				(width 0.1524)
				(type default)
			)
			(layer "B.SilkS")
		)
		(fp_line
			(start 0.7874 -0.4064)
			(end -0.7874 -0.4064)
			(stroke
				(width 0.1524)
				(type default)
			)
			(layer "B.SilkS")
		)
		(fp_line
			(start -0.7874 0.4064)
			(end 0.7874 0.4064)
			(stroke
				(width 0.1524)
				(type default)
			)
			(layer "B.SilkS")
		)
		(fp_line
			(start -0.7874 -0.4064)
			(end -0.7874 0.4064)
			(stroke
				(width 0.1524)
				(type default)
			)
			(layer "B.SilkS")
		)
		(fp_line
			(start 0.67945 0.3048)
			(end 0.67945 -0.305054)
			(stroke
				(width 0.1)
				(type default)
			)
			(layer "B.Fab")
		)
		(fp_line
			(start 0.67945 -0.305054)
			(end 0.12065 -0.305054)
			(stroke
				(width 0.1)
				(type default)
			)
			(layer "B.Fab")
		)
		(fp_line
			(start 0.12065 0.3048)
			(end 0.67945 0.3048)
			(stroke
				(width 0.1)
				(type default)
			)
			(layer "B.Fab")
		)
		(fp_line
			(start 0.12065 0.2794)
			(end 0.12065 0.3048)
			(stroke
				(width 0.1)
				(type default)
			)
			(layer "B.Fab")
		)
		(fp_line
			(start 0.12065 -0.2794)
			(end -0.12065 -0.2794)
			(stroke
				(width 0.1)
				(type default)
			)
			(layer "B.Fab")
		)
		(fp_line
			(start 0.12065 -0.305054)
			(end 0.12065 -0.2794)
			(stroke
				(width 0.1)
				(type default)
			)
			(layer "B.Fab")
		)
		(fp_line
			(start -0.120396 0.3048)
			(end -0.120396 0.2794)
			(stroke
				(width 0.1)
				(type default)
			)
			(layer "B.Fab")
		)
		(fp_line
			(start -0.120396 0.2794)
			(end 0.12065 0.2794)
			(stroke
				(width 0.1)
				(type default)
			)
			(layer "B.Fab")
		)
		(fp_line
			(start -0.12065 -0.2794)
			(end -0.12065 -0.3048)
			(stroke
				(width 0.1)
				(type default)
			)
			(layer "B.Fab")
		)
		(fp_line
			(start -0.12065 -0.3048)
			(end -0.67945 -0.3048)
			(stroke
				(width 0.1)
				(type default)
			)
			(layer "B.Fab")
		)
		(fp_line
			(start -0.67945 0.3048)
			(end -0.120396 0.3048)
			(stroke
				(width 0.1)
				(type default)
			)
			(layer "B.Fab")
		)
		(fp_line
			(start -0.67945 -0.3048)
			(end -0.67945 0.3048)
			(stroke
				(width 0.1)
				(type default)
			)
			(layer "B.Fab")
		)
		(pad "1" smd circle
			(at 0.40005 0)
			(size 0 0)
			(layers "B.Cu" "B.Mask" "B.Paste")
			(net "ROT_P1_RST_IND_N_R")
		)
		(pad "2" smd circle
			(at -0.40005 0)
			(size 0 0)
			(layers "B.Cu" "B.Mask" "B.Paste")
			(net "P3V3_AUX")
		)
	)
	(footprint ""
		(layer "B.Cu")
		(at 63.104268 -195.810378 -90)
		(property "Reference" "R4299"
			(at 0 0 90)
			(layer "B.SilkS")
			(hide yes)
			(effects
				(font
					(size 1.27 1.27)
				)
				(justify mirror)
			)
		)
		(property "Value" ""
			(at 0 0 90)
			(layer "B.Fab")
			(effects
				(font
					(size 1.27 1.27)
				)
				(justify mirror)
			)
		)
		(duplicate_pad_numbers_are_jumpers no)
		(fp_line
			(start -0.7874 0.4064)
			(end 0.7874 0.4064)
			(stroke
				(width 0.1524)
				(type default)
			)
			(layer "B.SilkS")
		)
		(fp_line
			(start 0.7874 0.4064)
			(end 0.7874 -0.4064)
			(stroke
				(width 0.1524)
				(type default)
			)
			(layer "B.SilkS")
		)
		(fp_line
			(start -0.7874 -0.4064)
			(end -0.7874 0.4064)
			(stroke
				(width 0.1524)
				(type default)
			)
			(layer "B.SilkS")
		)
		(fp_line
			(start 0.7874 -0.4064)
			(end -0.7874 -0.4064)
			(stroke
				(width 0.1524)
				(type default)
			)
			(layer "B.SilkS")
		)
		(fp_line
			(start -0.67945 0.3048)
			(end -0.120396 0.3048)
			(stroke
				(width 0.1)
				(type default)
			)
			(layer "B.Fab")
		)
		(fp_line
			(start -0.120396 0.3048)
			(end -0.120396 0.2794)
			(stroke
				(width 0.1)
				(type default)
			)
			(layer "B.Fab")
		)
		(fp_line
			(start 0.12065 0.3048)
			(end 0.67945 0.3048)
			(stroke
				(width 0.1)
				(type default)
			)
			(layer "B.Fab")
		)
		(fp_line
			(start 0.67945 0.3048)
			(end 0.67945 -0.305054)
			(stroke
				(width 0.1)
				(type default)
			)
			(layer "B.Fab")
		)
		(fp_line
			(start -0.120396 0.2794)
			(end 0.12065 0.2794)
			(stroke
				(width 0.1)
				(type default)
			)
			(layer "B.Fab")
		)
		(fp_line
			(start 0.12065 0.2794)
			(end 0.12065 0.3048)
			(stroke
				(width 0.1)
				(type default)
			)
			(layer "B.Fab")
		)
		(fp_line
			(start -0.12065 -0.2794)
			(end -0.12065 -0.3048)
			(stroke
				(width 0.1)
				(type default)
			)
			(layer "B.Fab")
		)
		(fp_line
			(start 0.12065 -0.2794)
			(end -0.12065 -0.2794)
			(stroke
				(width 0.1)
				(type default)
			)
			(layer "B.Fab")
		)
		(fp_line
			(start -0.67945 -0.3048)
			(end -0.67945 0.3048)
			(stroke
				(width 0.1)
				(type default)
			)
			(layer "B.Fab")
		)
		(fp_line
			(start -0.12065 -0.3048)
			(end -0.67945 -0.3048)
			(stroke
				(width 0.1)
				(type default)
			)
			(layer "B.Fab")
		)
		(fp_line
			(start 0.12065 -0.305054)
			(end 0.12065 -0.2794)
			(stroke
				(width 0.1)
				(type default)
			)
			(layer "B.Fab")
		)
		(fp_line
			(start 0.67945 -0.305054)
			(end 0.12065 -0.305054)
			(stroke
				(width 0.1)
				(type default)
			)
			(layer "B.Fab")
		)
		(pad "1" smd circle
			(at 0.40005 0 90)
			(size 0 0)
			(layers "B.Cu" "B.Mask" "B.Paste")
			(net "PWRGD_DRAMPWRGD_CPU1_AB_LVC1_R2")
		)
		(pad "2" smd circle
			(at -0.40005 0 90)
			(size 0 0)
			(layers "B.Cu" "B.Mask" "B.Paste")
			(net "PWRGD_DRAMPWRGD_CPU1_AB_LVC1_R")
		)
	)
)
